(kicad_pcb
	(version 20260206)
	(generator "pcbnew")
	(generator_version "10.0")
	(general
		(thickness 1.6)
		(legacy_teardrops no)
	)
	(paper "A4")
	(title_block
		(title "12092022_DA0F0TMDCD0_F0T_Management_Board_D_brd_V3_OCP.brd")
		(comment 1 "Grand Teton / footprints 1029-1034 of 1440")
	)
	(layers
		(0 "F.Cu" signal "TOP")
		(4 "In1.Cu" signal "GND")
		(6 "In2.Cu" signal "IN1")
		(8 "In3.Cu" signal "GND1")
		(10 "In4.Cu" signal "IN2")
		(12 "In5.Cu" signal "VCC")
		(14 "In6.Cu" signal "VCC1")
		(16 "In7.Cu" signal "IN3")
		(18 "In8.Cu" signal "GND2")
		(20 "In9.Cu" signal "IN4")
		(22 "In10.Cu" signal "GND3")
		(2 "B.Cu" signal "BOTTOM")
		(9 "F.Adhes" user "F.Adhesive")
		(11 "B.Adhes" user "B.Adhesive")
		(13 "F.Paste" user "Package Geometry/Pastemask Top")
		(15 "B.Paste" user "Package Geometry/Pastemask Bottom")
		(5 "F.SilkS" user "Ref Des/Silkscreen Top")
		(7 "B.SilkS" user "Ref Des/Silkscreen Bottom")
		(1 "F.Mask" user "Board Geometry/Soldermask Top")
		(3 "B.Mask" user "Board Geometry/Soldermask Bottom")
		(17 "Dwgs.User" user "User.Drawings")
		(19 "Cmts.User" user "User.Comments")
		(21 "Eco1.User" user "User.Eco1")
		(23 "Eco2.User" user "User.Eco2")
		(25 "Edge.Cuts" user "Board Geometry/Outline")
		(27 "Margin" user)
		(31 "F.CrtYd" user "Package Geometry/Place Bound Top")
		(29 "B.CrtYd" user "Package Geometry/Place Bound Bottom")
		(35 "F.Fab" user "Ref Des/Assembly Top")
		(33 "B.Fab" user "Ref Des/Assembly Bottom")
	)
	(footprint ""
		(layer "B.Cu")
		(at 48.624236 -30.857698 -90)
		(property "Reference" "R610"
			(at 0 0 90)
			(layer "B.SilkS")
			(hide yes)
			(effects
				(font
					(size 1.27 1.27)
				)
				(justify mirror)
			)
		)
		(property "Value" ""
			(at 0 0 90)
			(layer "B.Fab")
			(effects
				(font
					(size 1.27 1.27)
				)
				(justify mirror)
			)
		)
		(duplicate_pad_numbers_are_jumpers no)
		(fp_line
			(start -0.7874 0.4064)
			(end 0.7874 0.4064)
			(stroke
				(width 0.1524)
				(type default)
			)
			(layer "B.SilkS")
		)
		(fp_line
			(start 0.7874 0.4064)
			(end 0.7874 -0.4064)
			(stroke
				(width 0.1524)
				(type default)
			)
			(layer "B.SilkS")
		)
		(fp_line
			(start -0.7874 -0.4064)
			(end -0.7874 0.4064)
			(stroke
				(width 0.1524)
				(type default)
			)
			(layer "B.SilkS")
		)
		(fp_line
			(start 0.7874 -0.4064)
			(end -0.7874 -0.4064)
			(stroke
				(width 0.1524)
				(type default)
			)
			(layer "B.SilkS")
		)
		(fp_line
			(start -0.67945 0.3048)
			(end -0.120396 0.3048)
			(stroke
				(width 0.1)
				(type default)
			)
			(layer "B.Fab")
		)
		(fp_line
			(start -0.120396 0.3048)
			(end -0.120396 0.2794)
			(stroke
				(width 0.1)
				(type default)
			)
			(layer "B.Fab")
		)
		(fp_line
			(start 0.12065 0.3048)
			(end 0.67945 0.3048)
			(stroke
				(width 0.1)
				(type default)
			)
			(layer "B.Fab")
		)
		(fp_line
			(start 0.67945 0.3048)
			(end 0.67945 -0.305054)
			(stroke
				(width 0.1)
				(type default)
			)
			(layer "B.Fab")
		)
		(fp_line
			(start -0.120396 0.2794)
			(end 0.12065 0.2794)
			(stroke
				(width 0.1)
				(type default)
			)
			(layer "B.Fab")
		)
		(fp_line
			(start 0.12065 0.2794)
			(end 0.12065 0.3048)
			(stroke
				(width 0.1)
				(type default)
			)
			(layer "B.Fab")
		)
		(fp_line
			(start -0.12065 -0.2794)
			(end -0.12065 -0.3048)
			(stroke
				(width 0.1)
				(type default)
			)
			(layer "B.Fab")
		)
		(fp_line
			(start 0.12065 -0.2794)
			(end -0.12065 -0.2794)
			(stroke
				(width 0.1)
				(type default)
			)
			(layer "B.Fab")
		)
		(fp_line
			(start -0.67945 -0.3048)
			(end -0.67945 0.3048)
			(stroke
				(width 0.1)
				(type default)
			)
			(layer "B.Fab")
		)
		(fp_line
			(start -0.12065 -0.3048)
			(end -0.67945 -0.3048)
			(stroke
				(width 0.1)
				(type default)
			)
			(layer "B.Fab")
		)
		(fp_line
			(start 0.12065 -0.305054)
			(end 0.12065 -0.2794)
			(stroke
				(width 0.1)
				(type default)
			)
			(layer "B.Fab")
		)
		(fp_line
			(start 0.67945 -0.305054)
			(end 0.12065 -0.305054)
			(stroke
				(width 0.1)
				(type default)
			)
			(layer "B.Fab")
		)
		(pad "1" smd circle
			(at 0.40005 0 90)
			(size 0 0)
			(layers "B.Cu" "B.Mask" "B.Paste")
			(net "P3V3_AUX")
		)
		(pad "2" smd circle
			(at -0.40005 0 90)
			(size 0 0)
			(layers "B.Cu" "B.Mask" "B.Paste")
			(net "SMB_BMC_MM15_SCL")
		)
	)
	(footprint ""
		(layer "B.Cu")
		(at 59.042554 -45.939964 180)
		(property "Reference" "C45"
			(at 0 0 0)
			(layer "B.SilkS")
			(hide yes)
			(effects
				(font
					(size 1.27 1.27)
				)
				(justify mirror)
			)
		)
		(property "Value" ""
			(at 0 0 0)
			(layer "B.Fab")
			(effects
				(font
					(size 1.27 1.27)
				)
				(justify mirror)
			)
		)
		(duplicate_pad_numbers_are_jumpers no)
		(fp_line
			(start 0.7874 0.4064)
			(end 0.7874 -0.4064)
			(stroke
				(width 0.1524)
				(type default)
			)
			(layer "B.SilkS")
		)
		(fp_line
			(start 0.7874 -0.4064)
			(end -0.7874 -0.4064)
			(stroke
				(width 0.1524)
				(type default)
			)
			(layer "B.SilkS")
		)
		(fp_line
			(start -0.7874 0.4064)
			(end 0.7874 0.4064)
			(stroke
				(width 0.1524)
				(type default)
			)
			(layer "B.SilkS")
		)
		(fp_line
			(start -0.7874 -0.4064)
			(end -0.7874 0.4064)
			(stroke
				(width 0.1524)
				(type default)
			)
			(layer "B.SilkS")
		)
		(fp_line
			(start 0.67945 0.3048)
			(end 0.67945 -0.305054)
			(stroke
				(width 0.1)
				(type default)
			)
			(layer "B.Fab")
		)
		(fp_line
			(start 0.67945 -0.305054)
			(end 0.12065 -0.305054)
			(stroke
				(width 0.1)
				(type default)
			)
			(layer "B.Fab")
		)
		(fp_line
			(start 0.12065 0.3048)
			(end 0.67945 0.3048)
			(stroke
				(width 0.1)
				(type default)
			)
			(layer "B.Fab")
		)
		(fp_line
			(start 0.12065 0.2794)
			(end 0.12065 0.3048)
			(stroke
				(width 0.1)
				(type default)
			)
			(layer "B.Fab")
		)
		(fp_line
			(start 0.12065 -0.2794)
			(end -0.12065 -0.2794)
			(stroke
				(width 0.1)
				(type default)
			)
			(layer "B.Fab")
		)
		(fp_line
			(start 0.12065 -0.305054)
			(end 0.12065 -0.2794)
			(stroke
				(width 0.1)
				(type default)
			)
			(layer "B.Fab")
		)
		(fp_line
			(start -0.120396 0.3048)
			(end -0.120396 0.2794)
			(stroke
				(width 0.1)
				(type default)
			)
			(layer "B.Fab")
		)
		(fp_line
			(start -0.120396 0.2794)
			(end 0.12065 0.2794)
			(stroke
				(width 0.1)
				(type default)
			)
			(layer "B.Fab")
		)
		(fp_line
			(start -0.12065 -0.2794)
			(end -0.12065 -0.3048)
			(stroke
				(width 0.1)
				(type default)
			)
			(layer "B.Fab")
		)
		(fp_line
			(start -0.12065 -0.3048)
			(end -0.67945 -0.3048)
			(stroke
				(width 0.1)
				(type default)
			)
			(layer "B.Fab")
		)
		(fp_line
			(start -0.67945 0.3048)
			(end -0.120396 0.3048)
			(stroke
				(width 0.1)
				(type default)
			)
			(layer "B.Fab")
		)
		(fp_line
			(start -0.67945 -0.3048)
			(end -0.67945 0.3048)
			(stroke
				(width 0.1)
				(type default)
			)
			(layer "B.Fab")
		)
		(pad "1" smd circle
			(at 0.40005 0)
			(size 0 0)
			(layers "B.Cu" "B.Mask" "B.Paste")
			(net "P3V3_BMC_USB2AV33")
		)
		(pad "2" smd circle
			(at -0.40005 0)
			(size 0 0)
			(layers "B.Cu" "B.Mask" "B.Paste")
			(net "GND")
		)
	)
	(footprint ""
		(layer "B.Cu")
		(at 49.48682 -20.71624 -90)
		(property "Reference" "C157"
			(at 0 0 90)
			(layer "B.SilkS")
			(hide yes)
			(effects
				(font
					(size 1.27 1.27)
				)
				(justify mirror)
			)
		)
		(property "Value" ""
			(at 0 0 90)
			(layer "B.Fab")
			(effects
				(font
					(size 1.27 1.27)
				)
				(justify mirror)
			)
		)
		(duplicate_pad_numbers_are_jumpers no)
		(fp_line
			(start -0.7874 0.4064)
			(end 0.7874 0.4064)
			(stroke
				(width 0.1524)
				(type default)
			)
			(layer "B.SilkS")
		)
		(fp_line
			(start 0.7874 0.4064)
			(end 0.7874 -0.4064)
			(stroke
				(width 0.1524)
				(type default)
			)
			(layer "B.SilkS")
		)
		(fp_line
			(start -0.7874 -0.4064)
			(end -0.7874 0.4064)
			(stroke
				(width 0.1524)
				(type default)
			)
			(layer "B.SilkS")
		)
		(fp_line
			(start 0.7874 -0.4064)
			(end -0.7874 -0.4064)
			(stroke
				(width 0.1524)
				(type default)
			)
			(layer "B.SilkS")
		)
		(fp_line
			(start -0.67945 0.3048)
			(end -0.120396 0.3048)
			(stroke
				(width 0.1)
				(type default)
			)
			(layer "B.Fab")
		)
		(fp_line
			(start -0.120396 0.3048)
			(end -0.120396 0.2794)
			(stroke
				(width 0.1)
				(type default)
			)
			(layer "B.Fab")
		)
		(fp_line
			(start 0.12065 0.3048)
			(end 0.67945 0.3048)
			(stroke
				(width 0.1)
				(type default)
			)
			(layer "B.Fab")
		)
		(fp_line
			(start 0.67945 0.3048)
			(end 0.67945 -0.305054)
			(stroke
				(width 0.1)
				(type default)
			)
			(layer "B.Fab")
		)
		(fp_line
			(start -0.120396 0.2794)
			(end 0.12065 0.2794)
			(stroke
				(width 0.1)
				(type default)
			)
			(layer "B.Fab")
		)
		(fp_line
			(start 0.12065 0.2794)
			(end 0.12065 0.3048)
			(stroke
				(width 0.1)
				(type default)
			)
			(layer "B.Fab")
		)
		(fp_line
			(start -0.12065 -0.2794)
			(end -0.12065 -0.3048)
			(stroke
				(width 0.1)
				(type default)
			)
			(layer "B.Fab")
		)
		(fp_line
			(start 0.12065 -0.2794)
			(end -0.12065 -0.2794)
			(stroke
				(width 0.1)
				(type default)
			)
			(layer "B.Fab")
		)
		(fp_line
			(start -0.67945 -0.3048)
			(end -0.67945 0.3048)
			(stroke
				(width 0.1)
				(type default)
			)
			(layer "B.Fab")
		)
		(fp_line
			(start -0.12065 -0.3048)
			(end -0.67945 -0.3048)
			(stroke
				(width 0.1)
				(type default)
			)
			(layer "B.Fab")
		)
		(fp_line
			(start 0.12065 -0.305054)
			(end 0.12065 -0.2794)
			(stroke
				(width 0.1)
				(type default)
			)
			(layer "B.Fab")
		)
		(fp_line
			(start 0.67945 -0.305054)
			(end 0.12065 -0.305054)
			(stroke
				(width 0.1)
				(type default)
			)
			(layer "B.Fab")
		)
		(pad "1" smd circle
			(at 0.40005 0 90)
			(size 0 0)
			(layers "B.Cu" "B.Mask" "B.Paste")
			(net "P3V3_AUX")
		)
		(pad "2" smd circle
			(at -0.40005 0 90)
			(size 0 0)
			(layers "B.Cu" "B.Mask" "B.Paste")
			(net "GND")
		)
	)
	(footprint ""
		(layer "B.Cu")
		(at 14.097 -18.161 -90)
		(property "Reference" "R568"
			(at 0 0 90)
			(layer "B.SilkS")
			(hide yes)
			(effects
				(font
					(size 1.27 1.27)
				)
				(justify mirror)
			)
		)
		(property "Value" ""
			(at 0 0 90)
			(layer "B.Fab")
			(effects
				(font
					(size 1.27 1.27)
				)
				(justify mirror)
			)
		)
		(duplicate_pad_numbers_are_jumpers no)
		(fp_line
			(start -0.7874 0.4064)
			(end 0.7874 0.4064)
			(stroke
				(width 0.1524)
				(type default)
			)
			(layer "B.SilkS")
		)
		(fp_line
			(start 0.7874 0.4064)
			(end 0.7874 -0.4064)
			(stroke
				(width 0.1524)
				(type default)
			)
			(layer "B.SilkS")
		)
		(fp_line
			(start -0.7874 -0.4064)
			(end -0.7874 0.4064)
			(stroke
				(width 0.1524)
				(type default)
			)
			(layer "B.SilkS")
		)
		(fp_line
			(start 0.7874 -0.4064)
			(end -0.7874 -0.4064)
			(stroke
				(width 0.1524)
				(type default)
			)
			(layer "B.SilkS")
		)
		(fp_line
			(start -0.67945 0.3048)
			(end -0.120396 0.3048)
			(stroke
				(width 0.1)
				(type default)
			)
			(layer "B.Fab")
		)
		(fp_line
			(start -0.120396 0.3048)
			(end -0.120396 0.2794)
			(stroke
				(width 0.1)
				(type default)
			)
			(layer "B.Fab")
		)
		(fp_line
			(start 0.12065 0.3048)
			(end 0.67945 0.3048)
			(stroke
				(width 0.1)
				(type default)
			)
			(layer "B.Fab")
		)
		(fp_line
			(start 0.67945 0.3048)
			(end 0.67945 -0.305054)
			(stroke
				(width 0.1)
				(type default)
			)
			(layer "B.Fab")
		)
		(fp_line
			(start -0.120396 0.2794)
			(end 0.12065 0.2794)
			(stroke
				(width 0.1)
				(type default)
			)
			(layer "B.Fab")
		)
		(fp_line
			(start 0.12065 0.2794)
			(end 0.12065 0.3048)
			(stroke
				(width 0.1)
				(type default)
			)
			(layer "B.Fab")
		)
		(fp_line
			(start -0.12065 -0.2794)
			(end -0.12065 -0.3048)
			(stroke
				(width 0.1)
				(type default)
			)
			(layer "B.Fab")
		)
		(fp_line
			(start 0.12065 -0.2794)
			(end -0.12065 -0.2794)
			(stroke
				(width 0.1)
				(type default)
			)
			(layer "B.Fab")
		)
		(fp_line
			(start -0.67945 -0.3048)
			(end -0.67945 0.3048)
			(stroke
				(width 0.1)
				(type default)
			)
			(layer "B.Fab")
		)
		(fp_line
			(start -0.12065 -0.3048)
			(end -0.67945 -0.3048)
			(stroke
				(width 0.1)
				(type default)
			)
			(layer "B.Fab")
		)
		(fp_line
			(start 0.12065 -0.305054)
			(end 0.12065 -0.2794)
			(stroke
				(width 0.1)
				(type default)
			)
			(layer "B.Fab")
		)
		(fp_line
			(start 0.67945 -0.305054)
			(end 0.12065 -0.305054)
			(stroke
				(width 0.1)
				(type default)
			)
			(layer "B.Fab")
		)
		(pad "1" smd circle
			(at 0.40005 0 90)
			(size 0 0)
			(layers "B.Cu" "B.Mask" "B.Paste")
			(net "PWR_LED_P5V_AUX")
		)
		(pad "2" smd circle
			(at -0.40005 0 90)
			(size 0 0)
			(layers "B.Cu" "B.Mask" "B.Paste")
			(net "P5V_AUX")
		)
	)
	(footprint ""
		(layer "B.Cu")
		(at 48.461422 -55.170832 180)
		(property "Reference" "C77"
			(at 0 0 0)
			(layer "B.SilkS")
			(hide yes)
			(effects
				(font
					(size 1.27 1.27)
				)
				(justify mirror)
			)
		)
		(property "Value" ""
			(at 0 0 0)
			(layer "B.Fab")
			(effects
				(font
					(size 1.27 1.27)
				)
				(justify mirror)
			)
		)
		(duplicate_pad_numbers_are_jumpers no)
		(fp_line
			(start 0.7874 0.4064)
			(end 0.7874 -0.4064)
			(stroke
				(width 0.1524)
				(type default)
			)
			(layer "B.SilkS")
		)
		(fp_line
			(start 0.7874 -0.4064)
			(end -0.7874 -0.4064)
			(stroke
				(width 0.1524)
				(type default)
			)
			(layer "B.SilkS")
		)
		(fp_line
			(start -0.7874 0.4064)
			(end 0.7874 0.4064)
			(stroke
				(width 0.1524)
				(type default)
			)
			(layer "B.SilkS")
		)
		(fp_line
			(start -0.7874 -0.4064)
			(end -0.7874 0.4064)
			(stroke
				(width 0.1524)
				(type default)
			)
			(layer "B.SilkS")
		)
		(fp_line
			(start 0.67945 0.3048)
			(end 0.67945 -0.305054)
			(stroke
				(width 0.1)
				(type default)
			)
			(layer "B.Fab")
		)
		(fp_line
			(start 0.67945 -0.305054)
			(end 0.12065 -0.305054)
			(stroke
				(width 0.1)
				(type default)
			)
			(layer "B.Fab")
		)
		(fp_line
			(start 0.12065 0.3048)
			(end 0.67945 0.3048)
			(stroke
				(width 0.1)
				(type default)
			)
			(layer "B.Fab")
		)
		(fp_line
			(start 0.12065 0.2794)
			(end 0.12065 0.3048)
			(stroke
				(width 0.1)
				(type default)
			)
			(layer "B.Fab")
		)
		(fp_line
			(start 0.12065 -0.2794)
			(end -0.12065 -0.2794)
			(stroke
				(width 0.1)
				(type default)
			)
			(layer "B.Fab")
		)
		(fp_line
			(start 0.12065 -0.305054)
			(end 0.12065 -0.2794)
			(stroke
				(width 0.1)
				(type default)
			)
			(layer "B.Fab")
		)
		(fp_line
			(start -0.120396 0.3048)
			(end -0.120396 0.2794)
			(stroke
				(width 0.1)
				(type default)
			)
			(layer "B.Fab")
		)
		(fp_line
			(start -0.120396 0.2794)
			(end 0.12065 0.2794)
			(stroke
				(width 0.1)
				(type default)
			)
			(layer "B.Fab")
		)
		(fp_line
			(start -0.12065 -0.2794)
			(end -0.12065 -0.3048)
			(stroke
				(width 0.1)
				(type default)
			)
			(layer "B.Fab")
		)
		(fp_line
			(start -0.12065 -0.3048)
			(end -0.67945 -0.3048)
			(stroke
				(width 0.1)
				(type default)
			)
			(layer "B.Fab")
		)
		(fp_line
			(start -0.67945 0.3048)
			(end -0.120396 0.3048)
			(stroke
				(width 0.1)
				(type default)
			)
			(layer "B.Fab")
		)
		(fp_line
			(start -0.67945 -0.3048)
			(end -0.67945 0.3048)
			(stroke
				(width 0.1)
				(type default)
			)
			(layer "B.Fab")
		)
		(pad "1" smd circle
			(at 0.40005 0)
			(size 0 0)
			(layers "B.Cu" "B.Mask" "B.Paste")
			(net "A_BMC_ADCAV33")
		)
		(pad "2" smd circle
			(at -0.40005 0)
			(size 0 0)
			(layers "B.Cu" "B.Mask" "B.Paste")
			(net "GND")
		)
	)
	(footprint ""
		(layer "B.Cu")
		(at 57.75198 -30.867604 -90)
		(property "Reference" "R255"
			(at 0 0 90)
			(layer "B.SilkS")
			(hide yes)
			(effects
				(font
					(size 1.27 1.27)
				)
				(justify mirror)
			)
		)
		(property "Value" ""
			(at 0 0 90)
			(layer "B.Fab")
			(effects
				(font
					(size 1.27 1.27)
				)
				(justify mirror)
			)
		)
		(duplicate_pad_numbers_are_jumpers no)
		(fp_line
			(start -0.7874 0.4064)
			(end 0.7874 0.4064)
			(stroke
				(width 0.1524)
				(type default)
			)
			(layer "B.SilkS")
		)
		(fp_line
			(start 0.7874 0.4064)
			(end 0.7874 -0.4064)
			(stroke
				(width 0.1524)
				(type default)
			)
			(layer "B.SilkS")
		)
		(fp_line
			(start -0.7874 -0.4064)
			(end -0.7874 0.4064)
			(stroke
				(width 0.1524)
				(type default)
			)
			(layer "B.SilkS")
		)
		(fp_line
			(start 0.7874 -0.4064)
			(end -0.7874 -0.4064)
			(stroke
				(width 0.1524)
				(type default)
			)
			(layer "B.SilkS")
		)
		(fp_line
			(start -0.67945 0.3048)
			(end -0.120396 0.3048)
			(stroke
				(width 0.1)
				(type default)
			)
			(layer "B.Fab")
		)
		(fp_line
			(start -0.120396 0.3048)
			(end -0.120396 0.2794)
			(stroke
				(width 0.1)
				(type default)
			)
			(layer "B.Fab")
		)
		(fp_line
			(start 0.12065 0.3048)
			(end 0.67945 0.3048)
			(stroke
				(width 0.1)
				(type default)
			)
			(layer "B.Fab")
		)
		(fp_line
			(start 0.67945 0.3048)
			(end 0.67945 -0.305054)
			(stroke
				(width 0.1)
				(type default)
			)
			(layer "B.Fab")
		)
		(fp_line
			(start -0.120396 0.2794)
			(end 0.12065 0.2794)
			(stroke
				(width 0.1)
				(type default)
			)
			(layer "B.Fab")
		)
		(fp_line
			(start 0.12065 0.2794)
			(end 0.12065 0.3048)
			(stroke
				(width 0.1)
				(type default)
			)
			(layer "B.Fab")
		)
		(fp_line
			(start -0.12065 -0.2794)
			(end -0.12065 -0.3048)
			(stroke
				(width 0.1)
				(type default)
			)
			(layer "B.Fab")
		)
		(fp_line
			(start 0.12065 -0.2794)
			(end -0.12065 -0.2794)
			(stroke
				(width 0.1)
				(type default)
			)
			(layer "B.Fab")
		)
		(fp_line
			(start -0.67945 -0.3048)
			(end -0.67945 0.3048)
			(stroke
				(width 0.1)
				(type default)
			)
			(layer "B.Fab")
		)
		(fp_line
			(start -0.12065 -0.3048)
			(end -0.67945 -0.3048)
			(stroke
				(width 0.1)
				(type default)
			)
			(layer "B.Fab")
		)
		(fp_line
			(start 0.12065 -0.305054)
			(end 0.12065 -0.2794)
			(stroke
				(width 0.1)
				(type default)
			)
			(layer "B.Fab")
		)
		(fp_line
			(start 0.67945 -0.305054)
			(end 0.12065 -0.305054)
			(stroke
				(width 0.1)
				(type default)
			)
			(layer "B.Fab")
		)
		(pad "1" smd circle
			(at 0.40005 0 90)
			(size 0 0)
			(layers "B.Cu" "B.Mask" "B.Paste")
			(net "P3V3_AUX")
		)
		(pad "2" smd circle
			(at -0.40005 0 90)
			(size 0 0)
			(layers "B.Cu" "B.Mask" "B.Paste")
			(net "SMB_BMC_MM6_SDA")
		)
	)
)
